# SCM (Grand Teton) — schematic netlist excerpt (pin names and nets, part order shuffled) for the footprints in the layout excerpt that follows; sources: Cadence DE-HDL packaged netlist, KiCad conversion of 12092022_DA0F0TMDCD0_F0T_Management_Board_D_brd_V3_OCP.brd

R659  Q_RES  10K 1% EMPTY  pkg 0402LF  page 21 : A = P3V3_AUX ; B = EMMC_DT4_R
R850  Q_RES  33.2 1% CHIP  pkg 0402LF  page 21 : A = SMB_BMC_MM16_R5_SDA ; B = SMB_BMC_MM16_R1_SDA

(kicad_pcb
	(version 20260206)
	(generator "pcbnew")
	(generator_version "10.0")
	(general
		(thickness 1.6)
		(legacy_teardrops no)
	)
	(paper "A4")
	(title_block
		(title "12092022_DA0F0TMDCD0_F0T_Management_Board_D_brd_V3_OCP.brd")
		(comment 1 "Grand Teton / footprints 251-252 of 1440")
	)
	(layers
		(0 "F.Cu" signal "TOP")
		(4 "In1.Cu" signal "GND")
		(6 "In2.Cu" signal "IN1")
		(8 "In3.Cu" signal "GND1")
		(10 "In4.Cu" signal "IN2")
		(12 "In5.Cu" signal "VCC")
		(14 "In6.Cu" signal "VCC1")
		(16 "In7.Cu" signal "IN3")
		(18 "In8.Cu" signal "GND2")
		(20 "In9.Cu" signal "IN4")
		(22 "In10.Cu" signal "GND3")
		(2 "B.Cu" signal "BOTTOM")
		(9 "F.Adhes" user "F.Adhesive")
		(11 "B.Adhes" user "B.Adhesive")
		(13 "F.Paste" user "Package Geometry/Pastemask Top")
		(15 "B.Paste" user "Package Geometry/Pastemask Bottom")
		(5 "F.SilkS" user "Ref Des/Silkscreen Top")
		(7 "B.SilkS" user "Ref Des/Silkscreen Bottom")
		(1 "F.Mask" user "Board Geometry/Soldermask Top")
		(3 "B.Mask" user "Board Geometry/Soldermask Bottom")
		(17 "Dwgs.User" user "User.Drawings")
		(19 "Cmts.User" user "User.Comments")
		(21 "Eco1.User" user "User.Eco1")
		(23 "Eco2.User" user "User.Eco2")
		(25 "Edge.Cuts" user "Board Geometry/Outline")
		(27 "Margin" user)
		(31 "F.CrtYd" user "Package Geometry/Place Bound Top")
		(29 "B.CrtYd" user "Package Geometry/Place Bound Bottom")
		(35 "F.Fab" user "Ref Des/Assembly Top")
		(33 "B.Fab" user "Ref Des/Assembly Bottom")
	)
	(footprint ""
		(layer "F.Cu")
		(at 28.321 -68.453 90)
		(property "Reference" "R850"
			(at 0 0 90)
			(layer "F.SilkS")
			(hide yes)
			(effects
				(font
					(size 1.27 1.27)
				)
			)
		)
		(property "Value" ""
			(at 0 0 90)
			(layer "F.Fab")
			(effects
				(font
					(size 1.27 1.27)
				)
			)
		)
		(duplicate_pad_numbers_are_jumpers no)
		(fp_line
			(start 0.7874 -0.4064)
			(end 0.7874 0.4064)
			(stroke
				(width 0.1524)
				(type default)
			)
			(layer "F.SilkS")
		)
		(fp_line
			(start -0.7874 -0.4064)
			(end 0.7874 -0.4064)
			(stroke
				(width 0.1524)
				(type default)
			)
			(layer "F.SilkS")
		)
		(fp_line
			(start 0.7874 0.4064)
			(end -0.7874 0.4064)
			(stroke
				(width 0.1524)
				(type default)
			)
			(layer "F.SilkS")
		)
		(fp_line
			(start -0.7874 0.4064)
			(end -0.7874 -0.4064)
			(stroke
				(width 0.1524)
				(type default)
			)
			(layer "F.SilkS")
		)
		(fp_line
			(start -0.12065 -0.305054)
			(end -0.12065 -0.2794)
			(stroke
				(width 0.1)
				(type default)
			)
			(layer "F.Fab")
		)
		(fp_line
			(start -0.67945 -0.305054)
			(end -0.12065 -0.305054)
			(stroke
				(width 0.1)
				(type default)
			)
			(layer "F.Fab")
		)
		(fp_line
			(start 0.67945 -0.3048)
			(end 0.67945 0.3048)
			(stroke
				(width 0.1)
				(type default)
			)
			(layer "F.Fab")
		)
		(fp_line
			(start 0.12065 -0.3048)
			(end 0.67945 -0.3048)
			(stroke
				(width 0.1)
				(type default)
			)
			(layer "F.Fab")
		)
		(fp_line
			(start 0.12065 -0.2794)
			(end 0.12065 -0.3048)
			(stroke
				(width 0.1)
				(type default)
			)
			(layer "F.Fab")
		)
		(fp_line
			(start -0.12065 -0.2794)
			(end 0.12065 -0.2794)
			(stroke
				(width 0.1)
				(type default)
			)
			(layer "F.Fab")
		)
		(fp_line
			(start 0.120396 0.2794)
			(end -0.12065 0.2794)
			(stroke
				(width 0.1)
				(type default)
			)
			(layer "F.Fab")
		)
		(fp_line
			(start -0.12065 0.2794)
			(end -0.12065 0.3048)
			(stroke
				(width 0.1)
				(type default)
			)
			(layer "F.Fab")
		)
		(fp_line
			(start 0.67945 0.3048)
			(end 0.120396 0.3048)
			(stroke
				(width 0.1)
				(type default)
			)
			(layer "F.Fab")
		)
		(fp_line
			(start 0.120396 0.3048)
			(end 0.120396 0.2794)
			(stroke
				(width 0.1)
				(type default)
			)
			(layer "F.Fab")
		)
		(fp_line
			(start -0.12065 0.3048)
			(end -0.67945 0.3048)
			(stroke
				(width 0.1)
				(type default)
			)
			(layer "F.Fab")
		)
		(fp_line
			(start -0.67945 0.3048)
			(end -0.67945 -0.305054)
			(stroke
				(width 0.1)
				(type default)
			)
			(layer "F.Fab")
		)
		(pad "1" smd circle
			(at -0.40005 0 90)
			(size 0 0)
			(layers "F.Cu" "F.Mask" "F.Paste")
			(net "SMB_BMC_MM16_R5_SDA")
		)
		(pad "2" smd circle
			(at 0.40005 0 90)
			(size 0 0)
			(layers "F.Cu" "F.Mask" "F.Paste")
			(net "SMB_BMC_MM16_R1_SDA")
		)
	)
	(footprint ""
		(layer "F.Cu")
		(at 32.70504 -68.504054 90)
		(property "Reference" "R659"
			(at 0 0 90)
			(layer "F.SilkS")
			(hide yes)
			(effects
				(font
					(size 1.27 1.27)
				)
			)
		)
		(property "Value" ""
			(at 0 0 90)
			(layer "F.Fab")
			(effects
				(font
					(size 1.27 1.27)
				)
			)
		)
		(duplicate_pad_numbers_are_jumpers no)
		(fp_line
			(start 0.7874 -0.4064)
			(end 0.7874 0.4064)
			(stroke
				(width 0.1524)
				(type default)
			)
			(layer "F.SilkS")
		)
		(fp_line
			(start -0.7874 -0.4064)
			(end 0.7874 -0.4064)
			(stroke
				(width 0.1524)
				(type default)
			)
			(layer "F.SilkS")
		)
		(fp_line
			(start 0.7874 0.4064)
			(end -0.7874 0.4064)
			(stroke
				(width 0.1524)
				(type default)
			)
			(layer "F.SilkS")
		)
		(fp_line
			(start -0.7874 0.4064)
			(end -0.7874 -0.4064)
			(stroke
				(width 0.1524)
				(type default)
			)
			(layer "F.SilkS")
		)
		(fp_line
			(start -0.12065 -0.305054)
			(end -0.12065 -0.2794)
			(stroke
				(width 0.1)
				(type default)
			)
			(layer "F.Fab")
		)
		(fp_line
			(start -0.67945 -0.305054)
			(end -0.12065 -0.305054)
			(stroke
				(width 0.1)
				(type default)
			)
			(layer "F.Fab")
		)
		(fp_line
			(start 0.67945 -0.3048)
			(end 0.67945 0.3048)
			(stroke
				(width 0.1)
				(type default)
			)
			(layer "F.Fab")
		)
		(fp_line
			(start 0.12065 -0.3048)
			(end 0.67945 -0.3048)
			(stroke
				(width 0.1)
				(type default)
			)
			(layer "F.Fab")
		)
		(fp_line
			(start 0.12065 -0.2794)
			(end 0.12065 -0.3048)
			(stroke
				(width 0.1)
				(type default)
			)
			(layer "F.Fab")
		)
		(fp_line
			(start -0.12065 -0.2794)
			(end 0.12065 -0.2794)
			(stroke
				(width 0.1)
				(type default)
			)
			(layer "F.Fab")
		)
		(fp_line
			(start 0.120396 0.2794)
			(end -0.12065 0.2794)
			(stroke
				(width 0.1)
				(type default)
			)
			(layer "F.Fab")
		)
		(fp_line
			(start -0.12065 0.2794)
			(end -0.12065 0.3048)
			(stroke
				(width 0.1)
				(type default)
			)
			(layer "F.Fab")
		)
		(fp_line
			(start 0.67945 0.3048)
			(end 0.120396 0.3048)
			(stroke
				(width 0.1)
				(type default)
			)
			(layer "F.Fab")
		)
		(fp_line
			(start 0.120396 0.3048)
			(end 0.120396 0.2794)
			(stroke
				(width 0.1)
				(type default)
			)
			(layer "F.Fab")
		)
		(fp_line
			(start -0.12065 0.3048)
			(end -0.67945 0.3048)
			(stroke
				(width 0.1)
				(type default)
			)
			(layer "F.Fab")
		)
		(fp_line
			(start -0.67945 0.3048)
			(end -0.67945 -0.305054)
			(stroke
				(width 0.1)
				(type default)
			)
			(layer "F.Fab")
		)
		(pad "1" smd circle
			(at -0.40005 0 90)
			(size 0 0)
			(layers "F.Cu" "F.Mask" "F.Paste")
			(net "P3V3_AUX")
		)
		(pad "2" smd circle
			(at 0.40005 0 90)
			(size 0 0)
			(layers "F.Cu" "F.Mask" "F.Paste")
			(net "EMMC_DT4_R")
		)
	)
)
